FILE_TYPE = CONNECTIVITY;
{Allegro Design Entry HDL 17.4-2019 S026 (4007227) 1/17/2022}
"PAGE_NUMBER" = 463;
0"NC";
1"GND\g";
2"GND\g";
3"P1V8_CPU1_RT_1D\g";
4"GND\g";
5"RT_CPU1_P3_VQPS";
6"P1V8_CPU1_RT3_1A_1D\g";
7"P0V9_CPU1_RT_2D\g";
8"P0V9_CPU1_RT3_2A\g";
9"P0V9_CPU1_RT3_2A_2D\g";
10"P1V8_CPU1_RT3_1A\g";
11"GND\g";
12"NCF_CPU1_P3_GND";
13"NCF_A1_CPU1_P3_GND";
14"GND\g";
%"VCC_CORE"
"1","(-4675,5050)","0","pure_quanta_power","I10";
;
HDL_POWER"P0V9_CPU1_RT3_2A"
CDS_LIB"pure_quanta_power";
"A"8;
%"UNIVERSAL_GND"
"1","(-3125,1350)","0","pure_quanta_power","I11";
;
CDS_LIB"pure_quanta_power"
HDL_POWER"GND";
"A"14;
%"UNIVERSAL_GND"
"1","(-1450,975)","0","pure_quanta_power","I12";
;
CDS_LIB"pure_quanta_power"
HDL_POWER"GND";
"A"1;
%"Q_RES"
"2","(-1450,1275)","0","pure_quanta","I13";
;
LOCATION"R6903"
$SEC"1"
CDS_SEC"1"
MATERIAL"CHIP"
PACK_TYPE"0201LF"
TOLERANCE"5%"
WATTAGE"1/20W"
VALUE"0"
CDS_LIB"pure_quanta"
PART_NUMBER"CS00001JE10";
"A"
$PN"1"12;
"B"
$PN"2"1;
%"UNIVERSAL_GND"
"1","(-1300,1525)","0","pure_quanta_power","I14";
;
CDS_LIB"pure_quanta_power"
HDL_POWER"GND";
"A"2;
%"Q_RES"
"2","(-1300,1825)","0","pure_quanta","I15";
;
LOCATION"R6902"
$SEC"1"
CDS_SEC"1"
VALUE"0"
TOLERANCE"5%"
MATERIAL"CHIP"
PACK_TYPE"0201LF"
WATTAGE"1/20W"
CDS_LIB"pure_quanta"
PART_NUMBER"CS00001JE10";
"A"
$PN"1"13;
"B"
$PN"2"2;
%"UNIVERSAL_GND"
"1","(-1075,2075)","0","pure_quanta_power","I16";
;
CDS_LIB"pure_quanta_power"
HDL_POWER"GND";
"A"11;
%"PT5161LRS"
"5","(-2425,3600)","0","pure_quanta","I17";
;
LOCATION"U6017"
$SEC"5"
CDS_SEC"5"
PART_TYPE"SMLF"
VALUE"PT5161LRS"
MATERIAL"IC"
NEEDS_NO_SIZE"TRUE"
CDS_LMAN_SYM_OUTLINE"-350,2150,300,-2150"
CDS_LIB"pure_quanta"
PART_NUMBER"AJ051610U03";
"GND151"
$PN"V35"11;
"GND150"
$PN"V1"11;
"GND149"
$PN"U34"11;
"GND148"
$PN"U2"11;
"GND147"
$PN"T4"11;
"GND146"
$PN"T32"11;
"GND145"
$PN"T22"11;
"GND144"
$PN"T13"11;
"GND143"
$PN"L35"11;
"GND142"
$PN"L1"11;
"GND141"
$PN"K34"11;
"GND140"
$PN"K2"11;
"GND139"
$PN"J4"11;
"GND138"
$PN"J22"11;
"GND137"
$PN"H31"11;
"GND136"
$PN"H19"11;
"GND135"
$PN"H16"11;
"GND134"
$PN"H12"11;
"GND133"
$PN"FJ19"11;
"GND132"
$PN"FJ12"11;
"GND131"
$PN"FF21"11;
"GND130"
$PN"FF14"11;
"GND129"
$PN"FD35"11;
"GND128"
$PN"FD1"11;
"GND127"
$PN"FC9"11;
"GND126"
$PN"FC6"11;
"GND125"
$PN"FC3"11;
"GND124"
$PN"FC28"11;
"GND123"
$PN"FC25"11;
"GND122"
$PN"FC23"11;
"GND121"
$PN"FC19"11;
"GND120"
$PN"FB34"11;
"GND119"
$PN"FB2"11;
"GND118"
$PN"FA32"11;
"GND117"
$PN"FA15"11;
"GND116"
$PN"ET35"11;
"GND115"
$PN"ET1"11;
"GND114"
$PN"ER34"11;
"GND113"
$PN"ER2"11;
"GND112"
$PN"EP4"11;
"GND111"
$PN"EP32"11;
"GND110"
$PN"EP22"11;
"GND109"
$PN"EP13"11;
"GND108"
$PN"EJ35"11;
"GND107"
$PN"EJ1"11;
"GND106"
$PN"EH34"11;
"GND105"
$PN"EH2"11;
"GND104"
$PN"EG4"11;
"GND103"
$PN"EG32"11;
"GND102"
$PN"EG22"11;
"GND101"
$PN"EG13"11;
"GND100"
$PN"EB35"11;
"GND99"
$PN"EB1"11;
"GND98"
$PN"EA34"11;
"GND97"
$PN"EA2"11;
"GND96"
$PN"E33"11;
"GND95"
$PN"E27"11;
"GND94"
$PN"E14"11;
"GND93"
$PN"DY4"11;
"GND92"
$PN"DY32"11;
"GND91"
$PN"DY22"11;
"GND90"
$PN"DY13"11;
"GND89"
$PN"DR35"11;
"GND88"
$PN"DR1"11;
"GND87"
$PN"DP34"11;
"GND86"
$PN"DP2"11;
"GND85"
$PN"DN4"11;
"GND84"
$PN"DN32"11;
"GND83"
$PN"DN22"11;
"NCF_GND12"
$PN"FH34"12;
"NCF_GND11"
$PN"FH2"12;
"NCF_GND10"
$PN"FG35"12;
"NCF_GND9"
$PN"FG1"12;
"NCF_GND8"
$PN"FE34"12;
"NCF_GND7"
$PN"FE2"12;
"NCF_GND6"
$PN"D35"12;
"NCF_GND5"
$PN"D1"12;
"NCF_GND4"
$PN"C34"12;
"NCF_GND3"
$PN"C2"12;
"NCF_GND2"
$PN"A35"12;
"NCF_GND1"
$PN"A1"13;
"GND82"
$PN"DN13"14;
"GND81"
$PN"DH35"14;
"GND80"
$PN"DH1"14;
"GND79"
$PN"DG34"14;
"GND78"
$PN"DG2"14;
"GND77"
$PN"DF4"14;
"GND76"
$PN"DF32"14;
"GND75"
$PN"DF22"14;
"GND74"
$PN"DF13"14;
"GND73"
$PN"DA35"14;
"GND72"
$PN"DA1"14;
"GND71"
$PN"CY34"14;
"GND70"
$PN"CY2"14;
"GND69"
$PN"CW4"14;
"GND68"
$PN"CW32"14;
"GND67"
$PN"CW22"14;
"GND66"
$PN"CW13"14;
"GND65"
$PN"CP35"14;
"GND64"
$PN"CP1"14;
"GND63"
$PN"CN34"14;
"GND62"
$PN"CN2"14;
"GND61"
$PN"CM4"14;
"GND60"
$PN"CM32"14;
"GND59"
$PN"CM22"14;
"GND58"
$PN"CM13"14;
"GND57"
$PN"CG35"14;
"GND56"
$PN"CG1"14;
"GND55"
$PN"CF34"14;
"GND54"
$PN"CF2"14;
"GND53"
$PN"CE4"14;
"GND52"
$PN"CE32"14;
"GND51"
$PN"CE22"14;
"GND50"
$PN"CE13"14;
"GND49"
$PN"BY35"14;
"GND48"
$PN"BY1"14;
"GND47"
$PN"BW34"14;
"GND46"
$PN"BW2"14;
"GND45"
$PN"BV4"14;
"GND44"
$PN"BV32"14;
"GND43"
$PN"BV22"14;
"GND42"
$PN"BV13"14;
"GND41"
$PN"BN35"14;
"GND40"
$PN"BN1"14;
"GND39"
$PN"BM34"14;
"GND38"
$PN"BM2"14;
"GND37"
$PN"BL4"14;
"GND36"
$PN"BL32"14;
"GND35"
$PN"BL22"14;
"GND34"
$PN"BL13"14;
"GND33"
$PN"BF35"14;
"GND32"
$PN"BF1"14;
"GND31"
$PN"BE34"14;
"GND30"
$PN"BE2"14;
"GND29"
$PN"BD4"14;
"GND28"
$PN"BD32"14;
"GND27"
$PN"BD22"14;
"GND26"
$PN"BD13"14;
"GND25"
$PN"B19"14;
"GND24"
$PN"AW35"14;
"GND23"
$PN"AW1"14;
"GND22"
$PN"AV34"14;
"GND21"
$PN"AV2"14;
"GND20"
$PN"AU4"14;
"GND19"
$PN"AU32"14;
"GND18"
$PN"AU22"14;
"GND17"
$PN"AU13"14;
"GND16"
$PN"AM35"14;
"GND15"
$PN"AM1"14;
"GND14"
$PN"AL34"14;
"GND13"
$PN"AL2"14;
"GND12"
$PN"AK4"14;
"GND11"
$PN"AK32"14;
"GND10"
$PN"AK22"14;
"GND9"
$PN"AK13"14;
"GND8"
$PN"AE35"14;
"GND7"
$PN"AE1"14;
"GND6"
$PN"AD34"14;
"GND5"
$PN"AD2"14;
"GND4"
$PN"AC4"14;
"GND3"
$PN"AC32"14;
"GND2"
$PN"AC22"14;
"GND1"
$PN"AC13"14;
%"Q_RES"
"2","(-7650,3375)","0","pure_quanta","I18";
;
LOCATION"R6901"
$SEC"1"
CDS_SEC"1"
TOLERANCE"1%"
VALUE"200"
WATTAGE"1/20W"
MATERIAL"CHIP"
PACK_TYPE"0201LF"
CDS_LIB"pure_quanta"
PART_NUMBER"CS12001FE12";
"A"
$PN"1"5;
"B"
$PN"2"4;
%"Q_RES"
"2","(-8675,3925)","0","pure_quanta","I19";
;
LOCATION"R6900"
$SEC"1"
CDS_SEC"1"
MATERIAL"EMPTY"
VALUE"1K"
TOLERANCE"1%"
PACK_TYPE"0201LF"
WATTAGE"1/20W"
CDS_LIB"pure_quanta"
PART_NUMBER"CS21001FE07";
"A"
$PN"1"3;
"B"
$PN"2"5;
%"P1V0"
"1","(-8675,4150)","0","pure_quanta_power","I2";
;
HDL_POWER"P1V8_CPU1_RT_1D"
CDS_LIB"pure_quanta_power";
"A"3;
%"UNIVERSAL_GND"
"1","(-7650,3125)","0","pure_quanta_power","I3";
;
CDS_LIB"pure_quanta_power"
HDL_POWER"GND";
"A"4;
%"PT5161LRS"
"4","(-6500,4175)","0","pure_quanta","I5";
;
LOCATION"U6017"
$SEC"4"
CDS_SEC"4"
PART_TYPE"SMLF"
VALUE"PT5161LRS"
MATERIAL"IC"
NEEDS_NO_SIZE"TRUE"
CDS_LMAN_SYM_OUTLINE"-450,750,400,-750"
CDS_LIB"pure_quanta"
PART_NUMBER"AJ051610U03";
"PWR_2A_20"
$PN"T20"8;
"PWR_2A_19"
$PN"T17"8;
"PWR_2A_18"
$PN"EP20"8;
"PWR_2A_17"
$PN"EP17"8;
"PWR_2A_16"
$PN"EG20"8;
"PWR_2A_15"
$PN"EG17"8;
"PWR_2A_14"
$PN"DY20"8;
"PWR_2A_13"
$PN"DY17"8;
"PWR_2A_12"
$PN"DN20"8;
"PWR_2A_11"
$PN"DN17"8;
"PWR_2A_10"
$PN"DF20"9;
"PWR_2A_9"
$PN"DF17"9;
"PWR_2A_8"
$PN"BD20"9;
"PWR_2A_7"
$PN"BD17"9;
"PWR_2A_6"
$PN"AU20"8;
"PWR_2A_5"
$PN"AU17"8;
"PWR_2A_4"
$PN"AK20"8;
"PWR_2A_3"
$PN"AK17"8;
"PWR_2A_2"
$PN"AC20"8;
"PWR_2A_1"
$PN"AC17"8;
"PWR_1D"
$PN"BV17"6;
"PWR_2D_4"
$PN"CW20"7;
"PWR_2D_3"
$PN"CW17"7;
"PWR_2D_2"
$PN"BL20"7;
"PWR_2D_1"
$PN"BL17"7;
"PWR_1A_5"
$PN"CM20"10;
"PWR_1A_4"
$PN"CM17"10;
"PWR_1A_3"
$PN"CE20"10;
"PWR_1A_2"
$PN"CE17"10;
"PWR_1A_1"
$PN"BV20"10;
"VQPS"
$PN"G1"5;
%"P1V0"
"1","(-4650,3825)","0","pure_quanta_power","I6";
;
HDL_POWER"P0V9_CPU1_RT_2D"
CDS_LIB"pure_quanta_power";
"A"7;
%"P1V0"
"1","(-8350,4425)","0","pure_quanta_power","I7";
;
HDL_POWER"P1V8_CPU1_RT3_1A_1D"
CDS_LIB"pure_quanta_power";
"A"6;
%"P1V0"
"1","(-7775,4875)","0","pure_quanta_power","I8";
;
HDL_POWER"P1V8_CPU1_RT3_1A"
CDS_LIB"pure_quanta_power";
"A"10;
%"VCC_CORE"
"1","(-5250,4575)","0","pure_quanta_power","I9";
;
HDL_POWER"P0V9_CPU1_RT3_2A_2D"
CDS_LIB"pure_quanta_power";
"A"9;
END.
